# S9S_MB_2U (Grand Teton) — schematic netlist excerpt (pin names and nets, part order shuffled) for the footprints in the layout excerpt that follows; sources: Cadence DE-HDL packaged netlist, KiCad conversion of 03242023_DA0F0TMBIJ0_F0T_Motherboard_J_brd_V01_OCP.brd

R2576  Q_RES  0 5% CHIP  pkg 0402LF  page 296 : A = PWRGD_PVCCD_HV_CPU1 ; B = PWRGD_PVCCD_HV_CPU1_R
R3894  Q_RES  49.9 1% CHIP  pkg 0402LF  page 101 : A = I3C_SPD_DDRABCD_CPU1_LVC1_SCL_3 ; B = I3C_SPD_DDRABCD_CPU1_LVC1_SCL
C471  Q_CAP  47UF 4V 20% X6S  pkg C0805  page 78 : A = PVCCD_HV_CPU1 ; B = GND

(kicad_pcb
	(version 20260206)
	(generator "pcbnew")
	(generator_version "10.0")
	(general
		(thickness 1.6)
		(legacy_teardrops no)
	)
	(paper "A4")
	(title_block
		(title "03242023_DA0F0TMBIJ0_F0T_Motherboard_J_brd_V01_OCP.brd")
		(comment 1 "Grand Teton / footprints 5745-5747 of 6105")
	)
	(layers
		(0 "F.Cu" signal "TOP")
		(4 "In1.Cu" signal "GND")
		(6 "In2.Cu" signal "IN1")
		(8 "In3.Cu" signal "GND1")
		(10 "In4.Cu" signal "IN2")
		(12 "In5.Cu" signal "GND2")
		(14 "In6.Cu" signal "IN3")
		(16 "In7.Cu" signal "GND3")
		(18 "In8.Cu" signal "VCC")
		(20 "In9.Cu" signal "VCC1")
		(22 "In10.Cu" signal "GND4")
		(24 "In11.Cu" signal "IN4")
		(26 "In12.Cu" signal "GND5")
		(28 "In13.Cu" signal "IN5")
		(30 "In14.Cu" signal "GND6")
		(32 "In15.Cu" signal "IN6")
		(34 "In16.Cu" signal "GND7")
		(2 "B.Cu" signal "BOTTOM")
		(9 "F.Adhes" user "F.Adhesive")
		(11 "B.Adhes" user "B.Adhesive")
		(13 "F.Paste" user "Package Geometry/Pastemask Top")
		(15 "B.Paste" user "Package Geometry/Pastemask Bottom")
		(5 "F.SilkS" user "Ref Des/Silkscreen Top")
		(7 "B.SilkS" user "Ref Des/Silkscreen Bottom")
		(1 "F.Mask" user "Board Geometry/Soldermask Top")
		(3 "B.Mask" user "Board Geometry/Soldermask Bottom")
		(17 "Dwgs.User" user "User.Drawings")
		(19 "Cmts.User" user "User.Comments")
		(21 "Eco1.User" user "User.Eco1")
		(23 "Eco2.User" user "User.Eco2")
		(25 "Edge.Cuts" user "Board Geometry/Outline")
		(27 "Margin" user)
		(31 "F.CrtYd" user "Package Geometry/Place Bound Top")
		(29 "B.CrtYd" user "Package Geometry/Place Bound Bottom")
		(35 "F.Fab" user "Ref Des/Assembly Top")
		(33 "B.Fab" user "Ref Des/Assembly Bottom")
	)
	(footprint ""
		(layer "B.Cu")
		(at 21.914612 -168.437814 180)
		(property "Reference" "R2576"
			(at 0 0 0)
			(layer "B.SilkS")
			(hide yes)
			(effects
				(font
					(size 1.27 1.27)
				)
				(justify mirror)
			)
		)
		(property "Value" ""
			(at 0 0 0)
			(layer "B.Fab")
			(effects
				(font
					(size 1.27 1.27)
				)
				(justify mirror)
			)
		)
		(duplicate_pad_numbers_are_jumpers no)
		(fp_line
			(start 0.7874 0.4064)
			(end 0.7874 -0.4064)
			(stroke
				(width 0.1524)
				(type default)
			)
			(layer "B.SilkS")
		)
		(fp_line
			(start 0.7874 -0.4064)
			(end -0.7874 -0.4064)
			(stroke
				(width 0.1524)
				(type default)
			)
			(layer "B.SilkS")
		)
		(fp_line
			(start -0.7874 0.4064)
			(end 0.7874 0.4064)
			(stroke
				(width 0.1524)
				(type default)
			)
			(layer "B.SilkS")
		)
		(fp_line
			(start -0.7874 -0.4064)
			(end -0.7874 0.4064)
			(stroke
				(width 0.1524)
				(type default)
			)
			(layer "B.SilkS")
		)
		(fp_line
			(start 0.67945 0.3048)
			(end 0.67945 -0.305054)
			(stroke
				(width 0.1)
				(type default)
			)
			(layer "B.Fab")
		)
		(fp_line
			(start 0.67945 -0.305054)
			(end 0.12065 -0.305054)
			(stroke
				(width 0.1)
				(type default)
			)
			(layer "B.Fab")
		)
		(fp_line
			(start 0.12065 0.3048)
			(end 0.67945 0.3048)
			(stroke
				(width 0.1)
				(type default)
			)
			(layer "B.Fab")
		)
		(fp_line
			(start 0.12065 0.2794)
			(end 0.12065 0.3048)
			(stroke
				(width 0.1)
				(type default)
			)
			(layer "B.Fab")
		)
		(fp_line
			(start 0.12065 -0.2794)
			(end -0.12065 -0.2794)
			(stroke
				(width 0.1)
				(type default)
			)
			(layer "B.Fab")
		)
		(fp_line
			(start 0.12065 -0.305054)
			(end 0.12065 -0.2794)
			(stroke
				(width 0.1)
				(type default)
			)
			(layer "B.Fab")
		)
		(fp_line
			(start -0.120396 0.3048)
			(end -0.120396 0.2794)
			(stroke
				(width 0.1)
				(type default)
			)
			(layer "B.Fab")
		)
		(fp_line
			(start -0.120396 0.2794)
			(end 0.12065 0.2794)
			(stroke
				(width 0.1)
				(type default)
			)
			(layer "B.Fab")
		)
		(fp_line
			(start -0.12065 -0.2794)
			(end -0.12065 -0.3048)
			(stroke
				(width 0.1)
				(type default)
			)
			(layer "B.Fab")
		)
		(fp_line
			(start -0.12065 -0.3048)
			(end -0.67945 -0.3048)
			(stroke
				(width 0.1)
				(type default)
			)
			(layer "B.Fab")
		)
		(fp_line
			(start -0.67945 0.3048)
			(end -0.120396 0.3048)
			(stroke
				(width 0.1)
				(type default)
			)
			(layer "B.Fab")
		)
		(fp_line
			(start -0.67945 -0.3048)
			(end -0.67945 0.3048)
			(stroke
				(width 0.1)
				(type default)
			)
			(layer "B.Fab")
		)
		(pad "1" smd circle
			(at 0.40005 0)
			(size 0 0)
			(layers "B.Cu" "B.Mask" "B.Paste")
			(net "PWRGD_PVCCD_HV_CPU1")
		)
		(pad "2" smd circle
			(at -0.40005 0)
			(size 0 0)
			(layers "B.Cu" "B.Mask" "B.Paste")
			(net "PWRGD_PVCCD_HV_CPU1_R")
		)
	)
	(footprint ""
		(layer "B.Cu")
		(at 119.866918 -241.12347 90)
		(property "Reference" "C471"
			(at 0 0 90)
			(layer "B.SilkS")
			(hide yes)
			(effects
				(font
					(size 1.27 1.27)
				)
				(justify mirror)
			)
		)
		(property "Value" ""
			(at 0 0 90)
			(layer "B.Fab")
			(effects
				(font
					(size 1.27 1.27)
				)
				(justify mirror)
			)
		)
		(duplicate_pad_numbers_are_jumpers no)
		(fp_line
			(start 1.524 -0.762)
			(end -1.524 -0.762)
			(stroke
				(width 0.1524)
				(type default)
			)
			(layer "B.SilkS")
		)
		(fp_line
			(start -1.524 -0.762)
			(end -1.524 0.762)
			(stroke
				(width 0.1524)
				(type default)
			)
			(layer "B.SilkS")
		)
		(fp_line
			(start 1.524 0.762)
			(end 1.524 -0.762)
			(stroke
				(width 0.1524)
				(type default)
			)
			(layer "B.SilkS")
		)
		(fp_line
			(start -1.524 0.762)
			(end 1.524 0.762)
			(stroke
				(width 0.1524)
				(type default)
			)
			(layer "B.SilkS")
		)
		(fp_line
			(start 1.1049 -0.724916)
			(end 1.1049 0.724916)
			(stroke
				(width 0.1)
				(type default)
			)
			(layer "B.Fab")
		)
		(fp_line
			(start -1.1049 -0.724916)
			(end 1.1049 -0.724916)
			(stroke
				(width 0.1)
				(type default)
			)
			(layer "B.Fab")
		)
		(fp_line
			(start 1.1049 0.724916)
			(end -1.1049 0.724916)
			(stroke
				(width 0.1)
				(type default)
			)
			(layer "B.Fab")
		)
		(fp_line
			(start -1.1049 0.724916)
			(end -1.1049 -0.724916)
			(stroke
				(width 0.1)
				(type default)
			)
			(layer "B.Fab")
		)
		(pad "1" smd rect
			(at 0.889 0 90)
			(size 1.016 1.27)
			(layers "B.Cu" "B.Mask" "B.Paste")
			(net "PVCCD_HV_CPU1")
		)
		(pad "2" smd rect
			(at -0.889 0 90)
			(size 1.016 1.27)
			(layers "B.Cu" "B.Mask" "B.Paste")
			(net "GND")
		)
	)
	(footprint ""
		(layer "B.Cu")
		(at 44.16171 -315.423804 90)
		(property "Reference" "R3894"
			(at 0 0 90)
			(layer "B.SilkS")
			(hide yes)
			(effects
				(font
					(size 1.27 1.27)
				)
				(justify mirror)
			)
		)
		(property "Value" ""
			(at 0 0 90)
			(layer "B.Fab")
			(effects
				(font
					(size 1.27 1.27)
				)
				(justify mirror)
			)
		)
		(duplicate_pad_numbers_are_jumpers no)
		(fp_line
			(start 0.7874 -0.4064)
			(end -0.7874 -0.4064)
			(stroke
				(width 0.1524)
				(type default)
			)
			(layer "B.SilkS")
		)
		(fp_line
			(start -0.7874 -0.4064)
			(end -0.7874 0.4064)
			(stroke
				(width 0.1524)
				(type default)
			)
			(layer "B.SilkS")
		)
		(fp_line
			(start 0.7874 0.4064)
			(end 0.7874 -0.4064)
			(stroke
				(width 0.1524)
				(type default)
			)
			(layer "B.SilkS")
		)
		(fp_line
			(start -0.7874 0.4064)
			(end 0.7874 0.4064)
			(stroke
				(width 0.1524)
				(type default)
			)
			(layer "B.SilkS")
		)
		(fp_line
			(start 0.67945 -0.305054)
			(end 0.12065 -0.305054)
			(stroke
				(width 0.1)
				(type default)
			)
			(layer "B.Fab")
		)
		(fp_line
			(start 0.12065 -0.305054)
			(end 0.12065 -0.2794)
			(stroke
				(width 0.1)
				(type default)
			)
			(layer "B.Fab")
		)
		(fp_line
			(start -0.12065 -0.3048)
			(end -0.67945 -0.3048)
			(stroke
				(width 0.1)
				(type default)
			)
			(layer "B.Fab")
		)
		(fp_line
			(start -0.67945 -0.3048)
			(end -0.67945 0.3048)
			(stroke
				(width 0.1)
				(type default)
			)
			(layer "B.Fab")
		)
		(fp_line
			(start 0.12065 -0.2794)
			(end -0.12065 -0.2794)
			(stroke
				(width 0.1)
				(type default)
			)
			(layer "B.Fab")
		)
		(fp_line
			(start -0.12065 -0.2794)
			(end -0.12065 -0.3048)
			(stroke
				(width 0.1)
				(type default)
			)
			(layer "B.Fab")
		)
		(fp_line
			(start 0.12065 0.2794)
			(end 0.12065 0.3048)
			(stroke
				(width 0.1)
				(type default)
			)
			(layer "B.Fab")
		)
		(fp_line
			(start -0.120396 0.2794)
			(end 0.12065 0.2794)
			(stroke
				(width 0.1)
				(type default)
			)
			(layer "B.Fab")
		)
		(fp_line
			(start 0.67945 0.3048)
			(end 0.67945 -0.305054)
			(stroke
				(width 0.1)
				(type default)
			)
			(layer "B.Fab")
		)
		(fp_line
			(start 0.12065 0.3048)
			(end 0.67945 0.3048)
			(stroke
				(width 0.1)
				(type default)
			)
			(layer "B.Fab")
		)
		(fp_line
			(start -0.120396 0.3048)
			(end -0.120396 0.2794)
			(stroke
				(width 0.1)
				(type default)
			)
			(layer "B.Fab")
		)
		(fp_line
			(start -0.67945 0.3048)
			(end -0.120396 0.3048)
			(stroke
				(width 0.1)
				(type default)
			)
			(layer "B.Fab")
		)
		(pad "1" smd circle
			(at 0.40005 0 270)
			(size 0 0)
			(layers "B.Cu" "B.Mask" "B.Paste")
			(net "I3C_SPD_DDRABCD_CPU1_LVC1_SCL_3")
		)
		(pad "2" smd circle
			(at -0.40005 0 270)
			(size 0 0)
			(layers "B.Cu" "B.Mask" "B.Paste")
			(net "I3C_SPD_DDRABCD_CPU1_LVC1_SCL")
		)
	)
)
